(kicad_pcb
	(version 20260206)
	(generator "pcbnew")
	(generator_version "10.0")
	(general
		(thickness 1.6)
		(legacy_teardrops no)
	)
	(paper "A4")
	(title_block
		(title "Wiwynn_Tioga_Pass_MB.brd")
		(comment 1 "Tioga Pass / footprints 1142-1148 of 4770")
	)
	(layers
		(0 "F.Cu" signal "TOP")
		(4 "In1.Cu" signal "L2GND")
		(6 "In2.Cu" signal "L3")
		(8 "In3.Cu" signal "L4GND")
		(10 "In4.Cu" signal "L5")
		(12 "In5.Cu" signal "L6GND")
		(14 "In6.Cu" signal "L7VCC")
		(16 "In7.Cu" signal "L8VCC")
		(18 "In8.Cu" signal "L9GND")
		(20 "In9.Cu" signal "L10")
		(22 "In10.Cu" signal "L11GND")
		(24 "In11.Cu" signal "L12")
		(26 "In12.Cu" signal "L13GND")
		(2 "B.Cu" signal "BOTTOM")
		(9 "F.Adhes" user "F.Adhesive")
		(11 "B.Adhes" user "B.Adhesive")
		(13 "F.Paste" user "Package Geometry/Pastemask Top")
		(15 "B.Paste" user "Package Geometry/Pastemask Bottom")
		(5 "F.SilkS" user "Ref Des/Silkscreen Top")
		(7 "B.SilkS" user "Ref Des/Silkscreen Bottom")
		(1 "F.Mask" user "Board Geometry/Soldermask Top")
		(3 "B.Mask" user "Board Geometry/Soldermask Bottom")
		(17 "Dwgs.User" user "User.Drawings")
		(19 "Cmts.User" user "User.Comments")
		(21 "Eco1.User" user "User.Eco1")
		(23 "Eco2.User" user "User.Eco2")
		(25 "Edge.Cuts" user "Board Geometry/Outline")
		(27 "Margin" user)
		(31 "F.CrtYd" user "Package Geometry/Place Bound Top")
		(29 "B.CrtYd" user "Package Geometry/Place Bound Bottom")
		(35 "F.Fab" user "Ref Des/Assembly Top")
		(33 "B.Fab" user "Ref Des/Assembly Bottom")
	)
	(footprint ""
		(layer "F.Cu")
		(at 411.115256 -56.50484 -90)
		(property "Reference" "R8D24"
			(at 0 0 270)
			(layer "F.SilkS")
			(hide yes)
			(effects
				(font
					(size 1.27 1.27)
				)
			)
		)
		(property "Value" ""
			(at 0 0 270)
			(layer "F.Fab")
			(effects
				(font
					(size 1.27 1.27)
				)
			)
		)
		(duplicate_pad_numbers_are_jumpers no)
		(fp_poly
			(pts
				(xy -0.2794 -0.1016) (xy 0.2794 -0.1016) (xy 0.2794 0.9906) (xy -0.2794 0.9906)
			)
			(stroke
				(width 0)
				(type default)
			)
			(fill no)
			(layer "F.CrtYd")
		)
		(fp_line
			(start -0.2794 0.9906)
			(end 0.2794 0.9906)
			(stroke
				(width 0.1)
				(type default)
			)
			(layer "F.Fab")
		)
		(fp_line
			(start 0.2794 0.9906)
			(end 0.2794 -0.1016)
			(stroke
				(width 0.1)
				(type default)
			)
			(layer "F.Fab")
		)
		(fp_line
			(start -0.2794 -0.1016)
			(end -0.2794 0.9906)
			(stroke
				(width 0.1)
				(type default)
			)
			(layer "F.Fab")
		)
		(fp_line
			(start 0.2794 -0.1016)
			(end -0.2794 -0.1016)
			(stroke
				(width 0.1)
				(type default)
			)
			(layer "F.Fab")
		)
		(pad "1" smd rect
			(at 0 0 270)
			(size 0.508 0.508)
			(layers "F.Cu" "F.Mask" "F.Paste")
			(net "SMB_SENSOR_STBY_LVC3_SCL")
		)
		(pad "2" smd rect
			(at 0 0.889 270)
			(size 0.508 0.508)
			(layers "F.Cu" "F.Mask" "F.Paste")
			(net "SMB_SENSOR_STBY_LVC3_SCL_R2")
		)
		(zone
			(layer "F.Cu")
			(hatch none 0.5)
			(connect_pads
				(clearance 0)
			)
			(min_thickness 0.25)
			(keepout
				(tracks not_allowed)
				(vias allowed)
				(pads allowed)
				(copperpour not_allowed)
				(footprints allowed)
			)
			(placement
				(enabled no)
				(sheetname "")
			)
			(fill
				(thermal_gap 0.5)
				(thermal_bridge_width 0.5)
				(island_removal_mode 0)
			)
			(polygon
				(pts
					(xy 410.480256 -56.75884) (xy 410.480256 -56.25084) (xy 410.861256 -56.25084) (xy 410.861256 -56.75884)
				)
			)
		)
		(zone
			(layer "F.Cu")
			(hatch none 0.5)
			(connect_pads
				(clearance 0)
			)
			(min_thickness 0.25)
			(keepout
				(tracks allowed)
				(vias not_allowed)
				(pads allowed)
				(copperpour not_allowed)
				(footprints allowed)
			)
			(placement
				(enabled no)
				(sheetname "")
			)
			(fill
				(thermal_gap 0.5)
				(thermal_bridge_width 0.5)
				(island_removal_mode 0)
			)
			(polygon
				(pts
					(xy 410.861256 -56.75884) (xy 410.861256 -56.25084) (xy 410.480256 -56.25084) (xy 410.480256 -56.75884)
				)
			)
		)
	)
	(footprint ""
		(layer "F.Cu")
		(at 467.257892 -26.665936)
		(property "Reference" "R8E31"
			(at 0 0 0)
			(layer "F.SilkS")
			(hide yes)
			(effects
				(font
					(size 1.27 1.27)
				)
			)
		)
		(property "Value" ""
			(at 0 0 0)
			(layer "F.Fab")
			(effects
				(font
					(size 1.27 1.27)
				)
			)
		)
		(duplicate_pad_numbers_are_jumpers no)
		(fp_rect
			(start -0.2794 0.9906)
			(end 0.2794 -0.1016)
			(stroke
				(width 0)
				(type default)
			)
			(fill no)
			(layer "F.CrtYd")
		)
		(fp_line
			(start -0.2794 -0.1016)
			(end -0.2794 0.9906)
			(stroke
				(width 0.1)
				(type default)
			)
			(layer "F.Fab")
		)
		(fp_line
			(start -0.2794 0.9906)
			(end 0.2794 0.9906)
			(stroke
				(width 0.1)
				(type default)
			)
			(layer "F.Fab")
		)
		(fp_line
			(start 0.2794 -0.1016)
			(end -0.2794 -0.1016)
			(stroke
				(width 0.1)
				(type default)
			)
			(layer "F.Fab")
		)
		(fp_line
			(start 0.2794 0.9906)
			(end 0.2794 -0.1016)
			(stroke
				(width 0.1)
				(type default)
			)
			(layer "F.Fab")
		)
		(pad "1" smd rect
			(at 0 0)
			(size 0.508 0.508)
			(layers "F.Cu" "F.Mask" "F.Paste")
			(net "VSENSE_P3V3_STBY")
		)
		(pad "2" smd rect
			(at 0 0.889)
			(size 0.508 0.508)
			(layers "F.Cu" "F.Mask" "F.Paste")
			(net "VSENSE_VOUT_P3V3_STBY")
		)
		(zone
			(layer "F.Cu")
			(hatch none 0.5)
			(connect_pads
				(clearance 0)
			)
			(min_thickness 0.25)
			(keepout
				(tracks allowed)
				(vias not_allowed)
				(pads allowed)
				(copperpour not_allowed)
				(footprints allowed)
			)
			(placement
				(enabled no)
				(sheetname "")
			)
			(fill
				(thermal_gap 0.5)
				(thermal_bridge_width 0.5)
				(island_removal_mode 0)
			)
			(polygon
				(pts
					(xy 467.003892 -26.030936) (xy 467.511892 -26.030936) (xy 467.511892 -26.411936) (xy 467.003892 -26.411936)
				)
			)
		)
		(zone
			(layer "F.Cu")
			(hatch none 0.5)
			(connect_pads
				(clearance 0)
			)
			(min_thickness 0.25)
			(keepout
				(tracks not_allowed)
				(vias allowed)
				(pads allowed)
				(copperpour not_allowed)
				(footprints allowed)
			)
			(placement
				(enabled no)
				(sheetname "")
			)
			(fill
				(thermal_gap 0.5)
				(thermal_bridge_width 0.5)
				(island_removal_mode 0)
			)
			(polygon
				(pts
					(xy 467.003892 -26.030936) (xy 467.511892 -26.030936) (xy 467.511892 -26.411936) (xy 467.003892 -26.411936)
				)
			)
		)
	)
	(footprint ""
		(layer "F.Cu")
		(at 323.0245 -118.415816 90)
		(property "Reference" "C6B13"
			(at -0.8382 -0.67818 90)
			(unlocked yes)
			(layer "F.SilkS")
			(effects
				(font
					(size 0.4064 0.254)
					(thickness 0.1524)
				)
				(justify left)
			)
		)
		(property "Value" ""
			(at 0 0 90)
			(layer "F.Fab")
			(effects
				(font
					(size 1.27 1.27)
				)
			)
		)
		(duplicate_pad_numbers_are_jumpers no)
		(fp_poly
			(pts
				(xy 0.3048 -0.1016) (xy 0.3048 0.9906) (xy -0.3048 0.9906) (xy -0.3048 -0.1016)
			)
			(stroke
				(width 0)
				(type default)
			)
			(fill no)
			(layer "F.CrtYd")
		)
		(fp_line
			(start 0.3048 -0.1016)
			(end -0.3048 -0.1016)
			(stroke
				(width 0.1)
				(type default)
			)
			(layer "F.Fab")
		)
		(fp_line
			(start -0.3048 -0.1016)
			(end -0.3048 0.9906)
			(stroke
				(width 0.1)
				(type default)
			)
			(layer "F.Fab")
		)
		(fp_line
			(start 0.3048 0.9906)
			(end 0.3048 -0.1016)
			(stroke
				(width 0.1)
				(type default)
			)
			(layer "F.Fab")
		)
		(fp_line
			(start -0.3048 0.9906)
			(end 0.3048 0.9906)
			(stroke
				(width 0.1)
				(type default)
			)
			(layer "F.Fab")
		)
		(pad "1" smd rect
			(at 0 0 90)
			(size 0.508 0.508)
			(layers "F.Cu" "F.Mask" "F.Paste")
			(net "P3E_CPU0_PE1_PCH_TXP<11>")
		)
		(pad "2" smd rect
			(at 0 0.889 90)
			(size 0.508 0.508)
			(layers "F.Cu" "F.Mask" "F.Paste")
			(net "P3E_CPU0_PE1_PCH_C_TXP<11>")
		)
		(zone
			(layer "F.Cu")
			(hatch none 0.5)
			(connect_pads
				(clearance 0)
			)
			(min_thickness 0.25)
			(keepout
				(tracks allowed)
				(vias not_allowed)
				(pads allowed)
				(copperpour not_allowed)
				(footprints allowed)
			)
			(placement
				(enabled no)
				(sheetname "")
			)
			(fill
				(thermal_gap 0.5)
				(thermal_bridge_width 0.5)
				(island_removal_mode 0)
			)
			(polygon
				(pts
					(xy 323.2785 -118.161816) (xy 323.2785 -118.669816) (xy 323.6595 -118.669816) (xy 323.6595 -118.161816)
				)
			)
		)
		(zone
			(layer "F.Cu")
			(hatch none 0.5)
			(connect_pads
				(clearance 0)
			)
			(min_thickness 0.25)
			(keepout
				(tracks not_allowed)
				(vias allowed)
				(pads allowed)
				(copperpour not_allowed)
				(footprints allowed)
			)
			(placement
				(enabled no)
				(sheetname "")
			)
			(fill
				(thermal_gap 0.5)
				(thermal_bridge_width 0.5)
				(island_removal_mode 0)
			)
			(polygon
				(pts
					(xy 323.6595 -118.161816) (xy 323.6595 -118.669816) (xy 323.2785 -118.669816) (xy 323.2785 -118.161816)
				)
			)
		)
	)
	(footprint ""
		(layer "F.Cu")
		(at 416.511994 -47.828962 180)
		(property "Reference" "R25W64"
			(at -0.8382 -0.67818 180)
			(unlocked yes)
			(layer "F.SilkS")
			(effects
				(font
					(size 0.4064 0.254)
					(thickness 0.1524)
				)
				(justify left)
			)
		)
		(property "Value" ""
			(at 0 0 180)
			(layer "F.Fab")
			(effects
				(font
					(size 1.27 1.27)
				)
			)
		)
		(duplicate_pad_numbers_are_jumpers no)
		(fp_poly
			(pts
				(xy -0.2794 -0.1016) (xy 0.2794 -0.1016) (xy 0.2794 0.9906) (xy -0.2794 0.9906)
			)
			(stroke
				(width 0)
				(type default)
			)
			(fill no)
			(layer "F.CrtYd")
		)
		(fp_line
			(start 0.2794 0.9906)
			(end 0.2794 -0.1016)
			(stroke
				(width 0.1)
				(type default)
			)
			(layer "F.Fab")
		)
		(fp_line
			(start 0.2794 -0.1016)
			(end -0.2794 -0.1016)
			(stroke
				(width 0.1)
				(type default)
			)
			(layer "F.Fab")
		)
		(fp_line
			(start -0.2794 0.9906)
			(end 0.2794 0.9906)
			(stroke
				(width 0.1)
				(type default)
			)
			(layer "F.Fab")
		)
		(fp_line
			(start -0.2794 -0.1016)
			(end -0.2794 0.9906)
			(stroke
				(width 0.1)
				(type default)
			)
			(layer "F.Fab")
		)
		(pad "1" smd rect
			(at 0 0 180)
			(size 0.508 0.508)
			(layers "F.Cu" "F.Mask" "F.Paste")
			(net "P2E_SSB_BMC_TX_C_DP")
		)
		(pad "2" smd rect
			(at 0 0.889 180)
			(size 0.508 0.508)
			(layers "F.Cu" "F.Mask" "F.Paste")
			(net "GND")
		)
		(zone
			(layer "F.Cu")
			(hatch none 0.5)
			(connect_pads
				(clearance 0)
			)
			(min_thickness 0.25)
			(keepout
				(tracks not_allowed)
				(vias allowed)
				(pads allowed)
				(copperpour not_allowed)
				(footprints allowed)
			)
			(placement
				(enabled no)
				(sheetname "")
			)
			(fill
				(thermal_gap 0.5)
				(thermal_bridge_width 0.5)
				(island_removal_mode 0)
			)
			(polygon
				(pts
					(xy 416.765994 -48.463962) (xy 416.257994 -48.463962) (xy 416.257994 -48.082962) (xy 416.765994 -48.082962)
				)
			)
		)
		(zone
			(layer "F.Cu")
			(hatch none 0.5)
			(connect_pads
				(clearance 0)
			)
			(min_thickness 0.25)
			(keepout
				(tracks allowed)
				(vias not_allowed)
				(pads allowed)
				(copperpour not_allowed)
				(footprints allowed)
			)
			(placement
				(enabled no)
				(sheetname "")
			)
			(fill
				(thermal_gap 0.5)
				(thermal_bridge_width 0.5)
				(island_removal_mode 0)
			)
			(polygon
				(pts
					(xy 416.765994 -48.082962) (xy 416.257994 -48.082962) (xy 416.257994 -48.463962) (xy 416.765994 -48.463962)
				)
			)
		)
	)
	(footprint ""
		(layer "F.Cu")
		(at 320.6115 -124.587 -90)
		(property "Reference" "C830"
			(at -0.8382 -0.67818 270)
			(unlocked yes)
			(layer "F.SilkS")
			(effects
				(font
					(size 0.4064 0.254)
					(thickness 0.1524)
				)
				(justify left)
			)
		)
		(property "Value" ""
			(at 0 0 270)
			(layer "F.Fab")
			(effects
				(font
					(size 1.27 1.27)
				)
			)
		)
		(duplicate_pad_numbers_are_jumpers no)
		(fp_poly
			(pts
				(xy 0.3048 -0.1016) (xy 0.3048 0.9906) (xy -0.3048 0.9906) (xy -0.3048 -0.1016)
			)
			(stroke
				(width 0)
				(type default)
			)
			(fill no)
			(layer "F.CrtYd")
		)
		(fp_line
			(start -0.3048 0.9906)
			(end 0.3048 0.9906)
			(stroke
				(width 0.1)
				(type default)
			)
			(layer "F.Fab")
		)
		(fp_line
			(start 0.3048 0.9906)
			(end 0.3048 -0.1016)
			(stroke
				(width 0.1)
				(type default)
			)
			(layer "F.Fab")
		)
		(fp_line
			(start -0.3048 -0.1016)
			(end -0.3048 0.9906)
			(stroke
				(width 0.1)
				(type default)
			)
			(layer "F.Fab")
		)
		(fp_line
			(start 0.3048 -0.1016)
			(end -0.3048 -0.1016)
			(stroke
				(width 0.1)
				(type default)
			)
			(layer "F.Fab")
		)
		(pad "1" smd rect
			(at 0 0 270)
			(size 0.508 0.508)
			(layers "F.Cu" "F.Mask" "F.Paste")
			(net "P3E_CPU0_PE1_PCH_TXN<15>")
		)
		(pad "2" smd rect
			(at 0 0.889 270)
			(size 0.508 0.508)
			(layers "F.Cu" "F.Mask" "F.Paste")
			(net "P3E_CPU0_PE1_PCH_CON_TXN<15>")
		)
		(zone
			(layer "F.Cu")
			(hatch none 0.5)
			(connect_pads
				(clearance 0)
			)
			(min_thickness 0.25)
			(keepout
				(tracks not_allowed)
				(vias allowed)
				(pads allowed)
				(copperpour not_allowed)
				(footprints allowed)
			)
			(placement
				(enabled no)
				(sheetname "")
			)
			(fill
				(thermal_gap 0.5)
				(thermal_bridge_width 0.5)
				(island_removal_mode 0)
			)
			(polygon
				(pts
					(xy 319.9765 -124.841) (xy 319.9765 -124.333) (xy 320.3575 -124.333) (xy 320.3575 -124.841)
				)
			)
		)
		(zone
			(layer "F.Cu")
			(hatch none 0.5)
			(connect_pads
				(clearance 0)
			)
			(min_thickness 0.25)
			(keepout
				(tracks allowed)
				(vias not_allowed)
				(pads allowed)
				(copperpour not_allowed)
				(footprints allowed)
			)
			(placement
				(enabled no)
				(sheetname "")
			)
			(fill
				(thermal_gap 0.5)
				(thermal_bridge_width 0.5)
				(island_removal_mode 0)
			)
			(polygon
				(pts
					(xy 320.3575 -124.841) (xy 320.3575 -124.333) (xy 319.9765 -124.333) (xy 319.9765 -124.841)
				)
			)
		)
	)
	(footprint ""
		(layer "F.Cu")
		(at 155.532836 -119.267986 90)
		(property "Reference" "R3B3"
			(at 0 0 90)
			(layer "F.SilkS")
			(hide yes)
			(effects
				(font
					(size 1.27 1.27)
				)
			)
		)
		(property "Value" ""
			(at 0 0 90)
			(layer "F.Fab")
			(effects
				(font
					(size 1.27 1.27)
				)
			)
		)
		(duplicate_pad_numbers_are_jumpers no)
		(fp_poly
			(pts
				(xy -0.2794 -0.1016) (xy 0.2794 -0.1016) (xy 0.2794 0.9906) (xy -0.2794 0.9906)
			)
			(stroke
				(width 0)
				(type default)
			)
			(fill no)
			(layer "F.CrtYd")
		)
		(fp_line
			(start 0.2794 -0.1016)
			(end -0.2794 -0.1016)
			(stroke
				(width 0.1)
				(type default)
			)
			(layer "F.Fab")
		)
		(fp_line
			(start -0.2794 -0.1016)
			(end -0.2794 0.9906)
			(stroke
				(width 0.1)
				(type default)
			)
			(layer "F.Fab")
		)
		(fp_line
			(start 0.2794 0.9906)
			(end 0.2794 -0.1016)
			(stroke
				(width 0.1)
				(type default)
			)
			(layer "F.Fab")
		)
		(fp_line
			(start -0.2794 0.9906)
			(end 0.2794 0.9906)
			(stroke
				(width 0.1)
				(type default)
			)
			(layer "F.Fab")
		)
		(pad "1" smd rect
			(at 0 0 90)
			(size 0.508 0.508)
			(layers "F.Cu" "F.Mask" "F.Paste")
			(net "SVID_DIO0_CPU1")
		)
		(pad "2" smd rect
			(at 0 0.889 90)
			(size 0.508 0.508)
			(layers "F.Cu" "F.Mask" "F.Paste")
			(net "SVID_DIO0_CPU1_R")
		)
		(zone
			(layer "F.Cu")
			(hatch none 0.5)
			(connect_pads
				(clearance 0)
			)
			(min_thickness 0.25)
			(keepout
				(tracks allowed)
				(vias not_allowed)
				(pads allowed)
				(copperpour not_allowed)
				(footprints allowed)
			)
			(placement
				(enabled no)
				(sheetname "")
			)
			(fill
				(thermal_gap 0.5)
				(thermal_bridge_width 0.5)
				(island_removal_mode 0)
			)
			(polygon
				(pts
					(xy 155.786836 -119.013986) (xy 155.786836 -119.521986) (xy 156.167836 -119.521986) (xy 156.167836 -119.013986)
				)
			)
		)
		(zone
			(layer "F.Cu")
			(hatch none 0.5)
			(connect_pads
				(clearance 0)
			)
			(min_thickness 0.25)
			(keepout
				(tracks not_allowed)
				(vias allowed)
				(pads allowed)
				(copperpour not_allowed)
				(footprints allowed)
			)
			(placement
				(enabled no)
				(sheetname "")
			)
			(fill
				(thermal_gap 0.5)
				(thermal_bridge_width 0.5)
				(island_removal_mode 0)
			)
			(polygon
				(pts
					(xy 156.167836 -119.013986) (xy 156.167836 -119.521986) (xy 155.786836 -119.521986) (xy 155.786836 -119.013986)
				)
			)
		)
	)
	(footprint ""
		(layer "F.Cu")
		(at 26.543 -29.972 -90)
		(property "Reference" "R1F2"
			(at 0 0 270)
			(layer "F.SilkS")
			(hide yes)
			(effects
				(font
					(size 1.27 1.27)
				)
			)
		)
		(property "Value" ""
			(at 0 0 270)
			(layer "F.Fab")
			(effects
				(font
					(size 1.27 1.27)
				)
			)
		)
		(duplicate_pad_numbers_are_jumpers no)
		(fp_rect
			(start -0.2794 -0.1016)
			(end 0.2794 0.9906)
			(stroke
				(width 0)
				(type default)
			)
			(fill no)
			(layer "F.CrtYd")
		)
		(fp_line
			(start -0.2794 0.9906)
			(end 0.2794 0.9906)
			(stroke
				(width 0.1)
				(type default)
			)
			(layer "F.Fab")
		)
		(fp_line
			(start 0.2794 0.9906)
			(end 0.2794 -0.1016)
			(stroke
				(width 0.1)
				(type default)
			)
			(layer "F.Fab")
		)
		(fp_line
			(start -0.2794 -0.1016)
			(end -0.2794 0.9906)
			(stroke
				(width 0.1)
				(type default)
			)
			(layer "F.Fab")
		)
		(fp_line
			(start 0.2794 -0.1016)
			(end -0.2794 -0.1016)
			(stroke
				(width 0.1)
				(type default)
			)
			(layer "F.Fab")
		)
		(pad "1" smd rect
			(at 0 0 270)
			(size 0.508 0.508)
			(layers "F.Cu" "F.Mask" "F.Paste")
			(net "FAN_TACH0")
		)
		(pad "2" smd rect
			(at 0 0.889 270)
			(size 0.508 0.508)
			(layers "F.Cu" "F.Mask" "F.Paste")
			(net "FAN_TACH0_CPU0_D2")
		)
		(zone
			(layer "F.Cu")
			(hatch none 0.5)
			(connect_pads
				(clearance 0)
			)
			(min_thickness 0.25)
			(keepout
				(tracks not_allowed)
				(vias allowed)
				(pads allowed)
				(copperpour not_allowed)
				(footprints allowed)
			)
			(placement
				(enabled no)
				(sheetname "")
			)
			(fill
				(thermal_gap 0.5)
				(thermal_bridge_width 0.5)
				(island_removal_mode 0)
			)
			(polygon
				(pts
					(xy 26.289 -30.226) (xy 25.908 -30.226) (xy 25.908 -29.718) (xy 26.289 -29.718)
				)
			)
		)
		(zone
			(layer "F.Cu")
			(hatch none 0.5)
			(connect_pads
				(clearance 0)
			)
			(min_thickness 0.25)
			(keepout
				(tracks allowed)
				(vias not_allowed)
				(pads allowed)
				(copperpour not_allowed)
				(footprints allowed)
			)
			(placement
				(enabled no)
				(sheetname "")
			)
			(fill
				(thermal_gap 0.5)
				(thermal_bridge_width 0.5)
				(island_removal_mode 0)
			)
			(polygon
				(pts
					(xy 26.289 -30.226) (xy 25.908 -30.226) (xy 25.908 -29.718) (xy 26.289 -29.718)
				)
			)
		)
	)
)
